# S9S_MB_2U (Grand Teton) — schematic netlist excerpt (pin names and nets, part order shuffled) for the footprints in the layout excerpt that follows; sources: Cadence DE-HDL packaged netlist, KiCad conversion of 03242023_DA0F0TMBIJ0_F0T_Motherboard_J_brd_V01_OCP.brd

PC1855  Q_CAP  22UF 10V 20% X6S  pkg C0805  page 258 : A = P5V_AUX ; B = GND
R1719  Q_RES  33.2 1% CHIP  pkg 0402LF  page 154 : A = OCP_SFF_AUX_PWR_EN ; B = OCP_SFF_AUX_PWR_EN_R1
C956  Q_CAP_DIFFBUS  DIFF BUS_0.22UF 6.3V 20% X6S  pkg C0201  page 173 : \1\ = P5E_CPU0_PE2_TX_C_DN<4> ; \2\ = P5E_CPU0_PE2_TX_DN<4>

(kicad_pcb
	(version 20260206)
	(generator "pcbnew")
	(generator_version "10.0")
	(general
		(thickness 1.6)
		(legacy_teardrops no)
	)
	(paper "A4")
	(title_block
		(title "03242023_DA0F0TMBIJ0_F0T_Motherboard_J_brd_V01_OCP.brd")
		(comment 1 "Grand Teton / footprints 2993-2995 of 6105")
	)
	(layers
		(0 "F.Cu" signal "TOP")
		(4 "In1.Cu" signal "GND")
		(6 "In2.Cu" signal "IN1")
		(8 "In3.Cu" signal "GND1")
		(10 "In4.Cu" signal "IN2")
		(12 "In5.Cu" signal "GND2")
		(14 "In6.Cu" signal "IN3")
		(16 "In7.Cu" signal "GND3")
		(18 "In8.Cu" signal "VCC")
		(20 "In9.Cu" signal "VCC1")
		(22 "In10.Cu" signal "GND4")
		(24 "In11.Cu" signal "IN4")
		(26 "In12.Cu" signal "GND5")
		(28 "In13.Cu" signal "IN5")
		(30 "In14.Cu" signal "GND6")
		(32 "In15.Cu" signal "IN6")
		(34 "In16.Cu" signal "GND7")
		(2 "B.Cu" signal "BOTTOM")
		(9 "F.Adhes" user "F.Adhesive")
		(11 "B.Adhes" user "B.Adhesive")
		(13 "F.Paste" user "Package Geometry/Pastemask Top")
		(15 "B.Paste" user "Package Geometry/Pastemask Bottom")
		(5 "F.SilkS" user "Ref Des/Silkscreen Top")
		(7 "B.SilkS" user "Ref Des/Silkscreen Bottom")
		(1 "F.Mask" user "Board Geometry/Soldermask Top")
		(3 "B.Mask" user "Board Geometry/Soldermask Bottom")
		(17 "Dwgs.User" user "User.Drawings")
		(19 "Cmts.User" user "User.Comments")
		(21 "Eco1.User" user "User.Eco1")
		(23 "Eco2.User" user "User.Eco2")
		(25 "Edge.Cuts" user "Board Geometry/Outline")
		(27 "Margin" user)
		(31 "F.CrtYd" user "Package Geometry/Place Bound Top")
		(29 "B.CrtYd" user "Package Geometry/Place Bound Bottom")
		(35 "F.Fab" user "Ref Des/Assembly Top")
		(33 "B.Fab" user "Ref Des/Assembly Bottom")
	)
	(footprint ""
		(layer "F.Cu")
		(at 455.439526 -99.124008)
		(property "Reference" "R1719"
			(at 0 0 0)
			(layer "F.SilkS")
			(hide yes)
			(effects
				(font
					(size 1.27 1.27)
				)
			)
		)
		(property "Value" ""
			(at 0 0 0)
			(layer "F.Fab")
			(effects
				(font
					(size 1.27 1.27)
				)
			)
		)
		(duplicate_pad_numbers_are_jumpers no)
		(fp_line
			(start -0.7874 -0.4064)
			(end 0.7874 -0.4064)
			(stroke
				(width 0.1524)
				(type default)
			)
			(layer "F.SilkS")
		)
		(fp_line
			(start -0.7874 0.4064)
			(end -0.7874 -0.4064)
			(stroke
				(width 0.1524)
				(type default)
			)
			(layer "F.SilkS")
		)
		(fp_line
			(start 0.7874 -0.4064)
			(end 0.7874 0.4064)
			(stroke
				(width 0.1524)
				(type default)
			)
			(layer "F.SilkS")
		)
		(fp_line
			(start 0.7874 0.4064)
			(end -0.7874 0.4064)
			(stroke
				(width 0.1524)
				(type default)
			)
			(layer "F.SilkS")
		)
		(fp_line
			(start -0.67945 -0.305054)
			(end -0.12065 -0.305054)
			(stroke
				(width 0.1)
				(type default)
			)
			(layer "F.Fab")
		)
		(fp_line
			(start -0.67945 0.3048)
			(end -0.67945 -0.305054)
			(stroke
				(width 0.1)
				(type default)
			)
			(layer "F.Fab")
		)
		(fp_line
			(start -0.12065 -0.305054)
			(end -0.12065 -0.2794)
			(stroke
				(width 0.1)
				(type default)
			)
			(layer "F.Fab")
		)
		(fp_line
			(start -0.12065 -0.2794)
			(end 0.12065 -0.2794)
			(stroke
				(width 0.1)
				(type default)
			)
			(layer "F.Fab")
		)
		(fp_line
			(start -0.12065 0.2794)
			(end -0.12065 0.3048)
			(stroke
				(width 0.1)
				(type default)
			)
			(layer "F.Fab")
		)
		(fp_line
			(start -0.12065 0.3048)
			(end -0.67945 0.3048)
			(stroke
				(width 0.1)
				(type default)
			)
			(layer "F.Fab")
		)
		(fp_line
			(start 0.120396 0.2794)
			(end -0.12065 0.2794)
			(stroke
				(width 0.1)
				(type default)
			)
			(layer "F.Fab")
		)
		(fp_line
			(start 0.120396 0.3048)
			(end 0.120396 0.2794)
			(stroke
				(width 0.1)
				(type default)
			)
			(layer "F.Fab")
		)
		(fp_line
			(start 0.12065 -0.3048)
			(end 0.67945 -0.3048)
			(stroke
				(width 0.1)
				(type default)
			)
			(layer "F.Fab")
		)
		(fp_line
			(start 0.12065 -0.2794)
			(end 0.12065 -0.3048)
			(stroke
				(width 0.1)
				(type default)
			)
			(layer "F.Fab")
		)
		(fp_line
			(start 0.67945 -0.3048)
			(end 0.67945 0.3048)
			(stroke
				(width 0.1)
				(type default)
			)
			(layer "F.Fab")
		)
		(fp_line
			(start 0.67945 0.3048)
			(end 0.120396 0.3048)
			(stroke
				(width 0.1)
				(type default)
			)
			(layer "F.Fab")
		)
		(pad "1" smd circle
			(at -0.40005 0)
			(size 0 0)
			(layers "F.Cu" "F.Mask" "F.Paste")
			(net "OCP_SFF_AUX_PWR_EN")
		)
		(pad "2" smd circle
			(at 0.40005 0)
			(size 0 0)
			(layers "F.Cu" "F.Mask" "F.Paste")
			(net "OCP_SFF_AUX_PWR_EN_R1")
		)
	)
	(footprint ""
		(layer "F.Cu")
		(at 437.425846 -383.51968 180)
		(property "Reference" "PC1855"
			(at 0 0 180)
			(layer "F.SilkS")
			(hide yes)
			(effects
				(font
					(size 1.27 1.27)
				)
			)
		)
		(property "Value" ""
			(at 0 0 180)
			(layer "F.Fab")
			(effects
				(font
					(size 1.27 1.27)
				)
			)
		)
		(duplicate_pad_numbers_are_jumpers no)
		(fp_line
			(start 1.524 0.762)
			(end -1.524 0.762)
			(stroke
				(width 0.1524)
				(type default)
			)
			(layer "F.SilkS")
		)
		(fp_line
			(start 1.524 -0.762)
			(end 1.524 0.762)
			(stroke
				(width 0.1524)
				(type default)
			)
			(layer "F.SilkS")
		)
		(fp_line
			(start -1.524 0.762)
			(end -1.524 -0.762)
			(stroke
				(width 0.1524)
				(type default)
			)
			(layer "F.SilkS")
		)
		(fp_line
			(start -1.524 -0.762)
			(end 1.524 -0.762)
			(stroke
				(width 0.1524)
				(type default)
			)
			(layer "F.SilkS")
		)
		(fp_line
			(start 1.1049 0.724916)
			(end 1.1049 -0.724916)
			(stroke
				(width 0.1)
				(type default)
			)
			(layer "F.Fab")
		)
		(fp_line
			(start 1.1049 -0.724916)
			(end -1.1049 -0.724916)
			(stroke
				(width 0.1)
				(type default)
			)
			(layer "F.Fab")
		)
		(fp_line
			(start -1.1049 0.724916)
			(end 1.1049 0.724916)
			(stroke
				(width 0.1)
				(type default)
			)
			(layer "F.Fab")
		)
		(fp_line
			(start -1.1049 -0.724916)
			(end -1.1049 0.724916)
			(stroke
				(width 0.1)
				(type default)
			)
			(layer "F.Fab")
		)
		(pad "1" smd rect
			(at -0.889 0)
			(size 1.016 1.27)
			(layers "F.Cu" "F.Mask" "F.Paste")
			(net "P5V_AUX")
		)
		(pad "2" smd rect
			(at 0.889 0)
			(size 1.016 1.27)
			(layers "F.Cu" "F.Mask" "F.Paste")
			(net "GND")
		)
	)
	(footprint ""
		(layer "F.Cu")
		(at 406.00757 -402.371052 -90)
		(property "Reference" "C956"
			(at 0 0 270)
			(layer "F.SilkS")
			(hide yes)
			(effects
				(font
					(size 1.27 1.27)
				)
			)
		)
		(property "Value" ""
			(at 0 0 270)
			(layer "F.Fab")
			(effects
				(font
					(size 1.27 1.27)
				)
			)
		)
		(duplicate_pad_numbers_are_jumpers no)
		(fp_line
			(start -0.299974 0.150114)
			(end -0.299974 -0.150114)
			(stroke
				(width 0.1)
				(type default)
			)
			(layer "F.Fab")
		)
		(fp_line
			(start 0.299974 0.150114)
			(end -0.299974 0.150114)
			(stroke
				(width 0.1)
				(type default)
			)
			(layer "F.Fab")
		)
		(fp_line
			(start -0.299974 -0.150114)
			(end 0.299974 -0.150114)
			(stroke
				(width 0.1)
				(type default)
			)
			(layer "F.Fab")
		)
		(fp_line
			(start 0.299974 -0.150114)
			(end 0.299974 0.150114)
			(stroke
				(width 0.1)
				(type default)
			)
			(layer "F.Fab")
		)
		(pad "1" smd rect
			(at -0.2667 0 270)
			(size 0.3048 0.381)
			(layers "F.Cu" "F.Mask" "F.Paste")
			(net "P5E_CPU0_PE2_TX_C_DN<4>")
		)
		(pad "2" smd rect
			(at 0.2667 0 270)
			(size 0.3048 0.381)
			(layers "F.Cu" "F.Mask" "F.Paste")
			(net "P5E_CPU0_PE2_TX_DN<4>")
		)
	)
)
